# S9S_MB_2U (Grand Teton) — schematic netlist excerpt (pin names and nets, part order shuffled) for the footprints in the layout excerpt that follows; sources: Cadence DE-HDL packaged netlist, KiCad conversion of 03242023_DA0F0TMBIJ0_F0T_Motherboard_J_brd_V01_OCP.brd

Q71  MOSFET_NCH_DUAL  PJT138K IC  pkg SOT363XD  page 148
  S1  = GND
  G1  = FM_SWB_PWRGD
  D2  = FM_SWB_PWRGD_ISO
  S2  = GND
  G2  = FM_SWB_PWRGD_N
  D1  = FM_SWB_PWRGD_N

D143  Q_LED  IC  pkg SMLF  page 255 : A = LED_P12V_PSU_R1 ; C = GND

(kicad_pcb
	(version 20260206)
	(generator "pcbnew")
	(generator_version "10.0")
	(general
		(thickness 1.6)
		(legacy_teardrops no)
	)
	(paper "A4")
	(title_block
		(title "03242023_DA0F0TMBIJ0_F0T_Motherboard_J_brd_V01_OCP.brd")
		(comment 1 "Grand Teton / footprints 564-565 of 6105")
	)
	(layers
		(0 "F.Cu" signal "TOP")
		(4 "In1.Cu" signal "GND")
		(6 "In2.Cu" signal "IN1")
		(8 "In3.Cu" signal "GND1")
		(10 "In4.Cu" signal "IN2")
		(12 "In5.Cu" signal "GND2")
		(14 "In6.Cu" signal "IN3")
		(16 "In7.Cu" signal "GND3")
		(18 "In8.Cu" signal "VCC")
		(20 "In9.Cu" signal "VCC1")
		(22 "In10.Cu" signal "GND4")
		(24 "In11.Cu" signal "IN4")
		(26 "In12.Cu" signal "GND5")
		(28 "In13.Cu" signal "IN5")
		(30 "In14.Cu" signal "GND6")
		(32 "In15.Cu" signal "IN6")
		(34 "In16.Cu" signal "GND7")
		(2 "B.Cu" signal "BOTTOM")
		(9 "F.Adhes" user "F.Adhesive")
		(11 "B.Adhes" user "B.Adhesive")
		(13 "F.Paste" user "Package Geometry/Pastemask Top")
		(15 "B.Paste" user "Package Geometry/Pastemask Bottom")
		(5 "F.SilkS" user "Ref Des/Silkscreen Top")
		(7 "B.SilkS" user "Ref Des/Silkscreen Bottom")
		(1 "F.Mask" user "Board Geometry/Soldermask Top")
		(3 "B.Mask" user "Board Geometry/Soldermask Bottom")
		(17 "Dwgs.User" user "User.Drawings")
		(19 "Cmts.User" user "User.Comments")
		(21 "Eco1.User" user "User.Eco1")
		(23 "Eco2.User" user "User.Eco2")
		(25 "Edge.Cuts" user "Board Geometry/Outline")
		(27 "Margin" user)
		(31 "F.CrtYd" user "Package Geometry/Place Bound Top")
		(29 "B.CrtYd" user "Package Geometry/Place Bound Bottom")
		(35 "F.Fab" user "Ref Des/Assembly Top")
		(33 "B.Fab" user "Ref Des/Assembly Bottom")
	)
	(footprint ""
		(layer "F.Cu")
		(at 428.179992 -386.171948)
		(property "Reference" "Q71"
			(at 0.546608 -2.16789 0)
			(unlocked yes)
			(layer "F.SilkS")
			(effects
				(font
					(size 0.7874 0.5842)
					(thickness 0.1524)
				)
				(justify left)
			)
		)
		(property "Value" ""
			(at 0 0 0)
			(layer "F.Fab")
			(effects
				(font
					(size 1.27 1.27)
				)
			)
		)
		(duplicate_pad_numbers_are_jumpers no)
		(fp_line
			(start -1.332738 -1.100074)
			(end -0.4826 -1.100074)
			(stroke
				(width 0.1524)
				(type default)
			)
			(layer "F.SilkS")
		)
		(fp_line
			(start -1.332738 1.100074)
			(end -1.332738 -1.100074)
			(stroke
				(width 0.1524)
				(type default)
			)
			(layer "F.SilkS")
		)
		(fp_line
			(start -0.4826 -1.100074)
			(end 0 -0.541274)
			(stroke
				(width 0.1524)
				(type default)
			)
			(layer "F.SilkS")
		)
		(fp_line
			(start 0 -0.541274)
			(end 0.4826 -1.100074)
			(stroke
				(width 0.1524)
				(type default)
			)
			(layer "F.SilkS")
		)
		(fp_line
			(start 0.4826 -1.100074)
			(end 1.332738 -1.100074)
			(stroke
				(width 0.1524)
				(type default)
			)
			(layer "F.SilkS")
		)
		(fp_line
			(start 1.332738 -1.100074)
			(end 1.332738 1.100074)
			(stroke
				(width 0.1524)
				(type default)
			)
			(layer "F.SilkS")
		)
		(fp_line
			(start 1.332738 1.100074)
			(end -1.332738 1.100074)
			(stroke
				(width 0.1524)
				(type default)
			)
			(layer "F.SilkS")
		)
		(fp_poly
			(pts
				(xy -0.639318 -2.126488) (xy -0.990346 -1.424432) (xy -1.341374 -2.126488)
			)
			(stroke
				(width 0)
				(type default)
			)
			(fill yes)
			(layer "F.SilkS")
		)
		(fp_line
			(start -0.674878 -1.100074)
			(end 0.674878 -1.100074)
			(stroke
				(width 0.1)
				(type default)
			)
			(layer "F.Fab")
		)
		(fp_line
			(start -0.674878 1.100074)
			(end -0.674878 -1.100074)
			(stroke
				(width 0.1)
				(type default)
			)
			(layer "F.Fab")
		)
		(fp_line
			(start 0.674878 -1.100074)
			(end 0.674878 1.100074)
			(stroke
				(width 0.1)
				(type default)
			)
			(layer "F.Fab")
		)
		(fp_line
			(start 0.674878 1.100074)
			(end -0.674878 1.100074)
			(stroke
				(width 0.1)
				(type default)
			)
			(layer "F.Fab")
		)
		(fp_poly
			(pts
				(xy -2.2352 -0.298958) (xy -2.2352 -1.001014) (xy -1.533144 -0.649986)
			)
			(stroke
				(width 0)
				(type default)
			)
			(fill yes)
			(layer "F.Fab")
		)
		(pad "1" smd rect
			(at -0.94996 -0.649986 90)
			(size 0.4318 0.508)
			(layers "F.Cu" "F.Mask" "F.Paste")
			(net "GND")
		)
		(pad "2" smd rect
			(at -0.94996 0 90)
			(size 0.4318 0.508)
			(layers "F.Cu" "F.Mask" "F.Paste")
			(net "FM_SWB_PWRGD")
		)
		(pad "3" smd rect
			(at -0.94996 0.649986 90)
			(size 0.4318 0.508)
			(layers "F.Cu" "F.Mask" "F.Paste")
			(net "FM_SWB_PWRGD_ISO")
		)
		(pad "4" smd rect
			(at 0.94996 0.649986 90)
			(size 0.4318 0.508)
			(layers "F.Cu" "F.Mask" "F.Paste")
			(net "GND")
		)
		(pad "5" smd rect
			(at 0.94996 0 90)
			(size 0.4318 0.508)
			(layers "F.Cu" "F.Mask" "F.Paste")
			(net "FM_SWB_PWRGD_N")
		)
		(pad "6" smd rect
			(at 0.94996 -0.649986 90)
			(size 0.4318 0.508)
			(layers "F.Cu" "F.Mask" "F.Paste")
			(net "FM_SWB_PWRGD_N")
		)
	)
	(footprint ""
		(layer "F.Cu")
		(at 42.708576 -58.655712)
		(property "Reference" "D143"
			(at 4.258564 -0.413258 0)
			(unlocked yes)
			(layer "F.SilkS")
			(effects
				(font
					(size 0.7874 0.5842)
					(thickness 0.1524)
				)
				(justify left)
			)
		)
		(property "Value" ""
			(at 0 0 0)
			(layer "F.Fab")
			(effects
				(font
					(size 1.27 1.27)
				)
			)
		)
		(duplicate_pad_numbers_are_jumpers no)
		(fp_line
			(start -0.90678 0.4826)
			(end -0.90678 -0.4699)
			(stroke
				(width 0.1524)
				(type default)
			)
			(layer "F.SilkS")
		)
		(fp_line
			(start -0.89408 -0.4826)
			(end 0.90678 -0.4826)
			(stroke
				(width 0.1524)
				(type default)
			)
			(layer "F.SilkS")
		)
		(fp_line
			(start -0.79248 -0.4826)
			(end 1.03378 -0.4826)
			(stroke
				(width 0.1524)
				(type default)
			)
			(layer "F.SilkS")
		)
		(fp_line
			(start -0.64008 -0.4826)
			(end 1.16078 -0.4826)
			(stroke
				(width 0.1524)
				(type default)
			)
			(layer "F.SilkS")
		)
		(fp_line
			(start 0.90678 -0.4826)
			(end 0.90678 0.4826)
			(stroke
				(width 0.1524)
				(type default)
			)
			(layer "F.SilkS")
		)
		(fp_line
			(start 0.90678 0.4826)
			(end -0.90678 0.4826)
			(stroke
				(width 0.1524)
				(type default)
			)
			(layer "F.SilkS")
		)
		(fp_line
			(start 1.03378 -0.4826)
			(end 1.03378 0.4826)
			(stroke
				(width 0.1524)
				(type default)
			)
			(layer "F.SilkS")
		)
		(fp_line
			(start 1.03378 0.4826)
			(end -0.79248 0.4826)
			(stroke
				(width 0.1524)
				(type default)
			)
			(layer "F.SilkS")
		)
		(fp_line
			(start 1.16078 -0.4826)
			(end 1.16078 0.4826)
			(stroke
				(width 0.1524)
				(type default)
			)
			(layer "F.SilkS")
		)
		(fp_line
			(start 1.16078 0.4826)
			(end -0.64008 0.4826)
			(stroke
				(width 0.1524)
				(type default)
			)
			(layer "F.SilkS")
		)
		(fp_line
			(start -0.499872 -0.249936)
			(end 0.499872 -0.249936)
			(stroke
				(width 0.1)
				(type default)
			)
			(layer "F.Fab")
		)
		(fp_line
			(start -0.499872 0.249936)
			(end -0.499872 -0.249936)
			(stroke
				(width 0.1)
				(type default)
			)
			(layer "F.Fab")
		)
		(fp_line
			(start 0.499872 -0.249936)
			(end 0.499872 0.249936)
			(stroke
				(width 0.1)
				(type default)
			)
			(layer "F.Fab")
		)
		(fp_line
			(start 0.499872 0.249936)
			(end -0.499872 0.249936)
			(stroke
				(width 0.1)
				(type default)
			)
			(layer "F.Fab")
		)
		(pad "A" smd rect
			(at -0.47498 0)
			(size 0.6096 0.7112)
			(layers "F.Cu" "F.Mask" "F.Paste")
			(net "LED_P12V_PSU_R1")
		)
		(pad "C" smd rect
			(at 0.47498 0)
			(size 0.6096 0.7112)
			(layers "F.Cu" "F.Mask" "F.Paste")
			(net "GND")
		)
	)
)
